(kicad_pcb
	(version 20221018)
	(generator pcbnew)
	(general
    (thickness 1.62)
  )
	(paper "A4")
	(title_block
    (title "ECP5 - Datacenter Secure Control Module (DC-SCM)")
    (date "2024-07-01")
    (rev "1.2.1")
		(comment 9 "footprints 376-383 of 506")
	)
	(layers
    (0 "F.Cu" signal)
    (1 "In1.Cu" power)
    (2 "In2.Cu" signal)
    (3 "In3.Cu" power)
    (4 "In4.Cu" power)
    (5 "In5.Cu" signal)
    (6 "In6.Cu" power)
    (31 "B.Cu" signal)
    (32 "B.Adhes" user "B.Adhesive")
    (33 "F.Adhes" user "F.Adhesive")
    (34 "B.Paste" user)
    (35 "F.Paste" user)
    (36 "B.SilkS" user "B.Silkscreen")
    (37 "F.SilkS" user "F.Silkscreen")
    (38 "B.Mask" user)
    (39 "F.Mask" user)
    (40 "Dwgs.User" user "User.Drawings")
    (41 "Cmts.User" user "User.Comments")
    (42 "Eco1.User" user "User.Eco1")
    (43 "Eco2.User" user "User.Eco2")
    (44 "Edge.Cuts" user)
    (45 "Margin" user)
    (46 "B.CrtYd" user "B.Courtyard")
    (47 "F.CrtYd" user "F.Courtyard")
    (48 "B.Fab" user)
    (49 "F.Fab" user)
  )
	(footprint "antmicro-footprints:C_0402_1005Metric" (layer "B.Cu")
    (at 101 99.55 -90)
    (descr "Capacitor SMD 0402")
    (tags "capacitor SMD 0402")
    (property "Author" "Antmicro")
    (property "Dielectric" "X7R")
    (property "License" "Apache-2.0")
    (property "MPN" "GRM155R71H103KA88D")
    (property "Manufacturer" "Murata")
    (property "Public" "False")
    (property "Sheetfile" "ethernet.kicad_sch")
    (property "Sheetname" "Ethernet")
    (property "Val" "10n")
    (property "Voltage" "50V")
    (property "ki_description" "SMD Multilayer Ceramic Capacitor, 10000 pF, 50 V, 0402 [1005 Metric], ± 10%, X7R, GRM Series")
    (property "ki_keywords" "0402, SMT, CAPACITOR, PASSIVE")
    (attr smd)
    (fp_text reference "C7" (at 0.345 0.82 90) (layer "B.SilkS")
        (effects (font (size 0.7 0.7) (thickness 0.127)) (justify mirror))
    )
    (fp_text value "C_10n_0402" (at 0 -1.17 90) (layer "B.Fab")
        (effects (font (size 1 1) (thickness 0.15)) (justify mirror))
    )
    (fp_text user "Author: Antmicro" (at -0.939 -3.399 90) (layer "B.Fab") hide
        (effects (font (size 0.7 0.7) (thickness 0.15)) (justify left bottom mirror))
    )
    (fp_text user "License: Apache-2.0" (at -0.939 -5.799 90) (layer "B.Fab") hide
        (effects (font (size 0.7 0.7) (thickness 0.15)) (justify left bottom mirror))
    )
    (fp_text user "${REFERENCE}" (at 0 0) (layer "B.Fab")
        (effects (font (size 0.25 0.25) (thickness 0.04)) (justify mirror))
    )
    (fp_rect (start -0.925 0.47) (end 0.925 -0.47)
      (stroke (width 0.05) (type default)) (fill none) (layer "B.CrtYd"))
    (fp_line (start -0.494 -0.248) (end -0.494 0.25)
      (stroke (width 0.15) (type solid)) (layer "B.Fab"))
    (fp_line (start -0.494 0.25) (end 0.504 0.25)
      (stroke (width 0.15) (type solid)) (layer "B.Fab"))
    (fp_line (start 0.504 -0.248) (end -0.494 -0.248)
      (stroke (width 0.15) (type solid)) (layer "B.Fab"))
    (fp_line (start 0.504 0.25) (end 0.504 -0.248)
      (stroke (width 0.15) (type solid)) (layer "B.Fab"))
    (pad "1" smd roundrect (at -0.48 0 270) (size 0.59 0.64) (layers "B.Cu" "B.Paste" "B.Mask") (roundrect_rratio 0.25)
      (net 1 "GND") (pintype "passive"))
    (pad "2" smd roundrect (at 0.48 0 270) (size 0.59 0.64) (layers "B.Cu" "B.Paste" "B.Mask") (roundrect_rratio 0.25)
      (net 211 "VCC1V2") (pintype "passive"))
  )
	(footprint "antmicro-footprints:C_0402_1005Metric" (layer "B.Cu")
    (at 105.04 99.55 -90)
    (descr "Capacitor SMD 0402")
    (tags "capacitor SMD 0402")
    (property "Author" "Antmicro")
    (property "Dielectric" "")
    (property "License" "Apache-2.0")
    (property "MPN" "GRM155R61A475MEAAD")
    (property "Manufacturer" "Murata")
    (property "Public" "False")
    (property "Sheetfile" "ethernet.kicad_sch")
    (property "Sheetname" "Ethernet")
    (property "Val" "4u7")
    (property "Voltage" "")
    (property "ki_description" "SMD Multilayer Ceramic Capacitor, 4.7 µF, 10 V, 0402 [1005 Metric], ± 20%, X5R, GRM Series")
    (property "ki_keywords" "0402, SMT, CAPACITOR, PASSIVE")
    (attr smd)
    (fp_text reference "C6" (at -1.555 0.03 90) (layer "B.SilkS")
        (effects (font (size 0.7 0.7) (thickness 0.127)) (justify mirror))
    )
    (fp_text value "C_4u7_0402" (at 0 -1.17 90) (layer "B.Fab")
        (effects (font (size 1 1) (thickness 0.15)) (justify mirror))
    )
    (fp_text user "Author: Antmicro" (at -0.939 -3.399 90) (layer "B.Fab") hide
        (effects (font (size 0.7 0.7) (thickness 0.15)) (justify left bottom mirror))
    )
    (fp_text user "${REFERENCE}" (at 0 0 90) (layer "B.Fab")
        (effects (font (size 0.25 0.25) (thickness 0.04)) (justify mirror))
    )
    (fp_text user "License: Apache-2.0" (at -0.939 -5.799 90) (layer "B.Fab") hide
        (effects (font (size 0.7 0.7) (thickness 0.15)) (justify left bottom mirror))
    )
    (fp_rect (start -0.925 0.47) (end 0.925 -0.47)
      (stroke (width 0.05) (type default)) (fill none) (layer "B.CrtYd"))
    (fp_line (start -0.494 -0.248) (end -0.494 0.25)
      (stroke (width 0.15) (type solid)) (layer "B.Fab"))
    (fp_line (start -0.494 0.25) (end 0.504 0.25)
      (stroke (width 0.15) (type solid)) (layer "B.Fab"))
    (fp_line (start 0.504 -0.248) (end -0.494 -0.248)
      (stroke (width 0.15) (type solid)) (layer "B.Fab"))
    (fp_line (start 0.504 0.25) (end 0.504 -0.248)
      (stroke (width 0.15) (type solid)) (layer "B.Fab"))
    (pad "1" smd roundrect (at -0.48 0 270) (size 0.59 0.64) (layers "B.Cu" "B.Paste" "B.Mask") (roundrect_rratio 0.25)
      (net 1 "GND") (pintype "passive"))
    (pad "2" smd roundrect (at 0.48 0 270) (size 0.59 0.64) (layers "B.Cu" "B.Paste" "B.Mask") (roundrect_rratio 0.25)
      (net 2 "VCC3V3") (pintype "passive"))
  )
	(footprint "antmicro-footprints:C_0402_1005Metric" (layer "B.Cu")
    (at 104.03 100.3 -90)
    (descr "Capacitor SMD 0402")
    (tags "capacitor SMD 0402")
    (property "Author" "Antmicro")
    (property "Dielectric" "")
    (property "License" "Apache-2.0")
    (property "MPN" "C1005X5R1E474M050BB")
    (property "Manufacturer" "TDK")
    (property "Public" "False")
    (property "Sheetfile" "ethernet.kicad_sch")
    (property "Sheetname" "Ethernet")
    (property "Val" "470n")
    (property "Voltage" "")
    (property "ki_description" "SMD Multilayer Ceramic Capacitor, 0.47 µF, 25 V, 0402 [1005 Metric], ± 20%, X5R, C")
    (property "ki_keywords" "0402, SMT, CAPACITOR, PASSIVE, CERAMIC, MLCC")
    (attr smd)
    (fp_text reference "C3" (at 1.575 -0.05 90) (layer "B.SilkS")
        (effects (font (size 0.7 0.7) (thickness 0.127)) (justify mirror))
    )
    (fp_text value "C_470n_0402" (at 0 -1.17 90) (layer "B.Fab")
        (effects (font (size 1 1) (thickness 0.15)) (justify mirror))
    )
    (fp_text user "License: Apache-2.0" (at -0.939 -5.799 90) (layer "B.Fab") hide
        (effects (font (size 0.7 0.7) (thickness 0.15)) (justify left bottom mirror))
    )
    (fp_text user "${REFERENCE}" (at 0 0 90) (layer "B.Fab")
        (effects (font (size 0.25 0.25) (thickness 0.04)) (justify mirror))
    )
    (fp_text user "Author: Antmicro" (at -0.939 -3.399 90) (layer "B.Fab") hide
        (effects (font (size 0.7 0.7) (thickness 0.15)) (justify left bottom mirror))
    )
    (fp_rect (start -0.925 0.47) (end 0.925 -0.47)
      (stroke (width 0.05) (type default)) (fill none) (layer "B.CrtYd"))
    (fp_line (start -0.494 -0.248) (end -0.494 0.25)
      (stroke (width 0.15) (type solid)) (layer "B.Fab"))
    (fp_line (start -0.494 0.25) (end 0.504 0.25)
      (stroke (width 0.15) (type solid)) (layer "B.Fab"))
    (fp_line (start 0.504 -0.248) (end -0.494 -0.248)
      (stroke (width 0.15) (type solid)) (layer "B.Fab"))
    (fp_line (start 0.504 0.25) (end 0.504 -0.248)
      (stroke (width 0.15) (type solid)) (layer "B.Fab"))
    (pad "1" smd roundrect (at -0.48 0 270) (size 0.59 0.64) (layers "B.Cu" "B.Paste" "B.Mask") (roundrect_rratio 0.25)
      (net 1 "GND") (pintype "passive"))
    (pad "2" smd roundrect (at 0.48 0 270) (size 0.59 0.64) (layers "B.Cu" "B.Paste" "B.Mask") (roundrect_rratio 0.25)
      (net 211 "VCC1V2") (pintype "passive"))
  )
	(footprint "antmicro-footprints:C_0402_1005Metric" (layer "B.Cu")
    (at 108.95 98.8 180)
    (descr "Capacitor SMD 0402")
    (tags "capacitor SMD 0402")
    (property "Author" "Antmicro")
    (property "Dielectric" "")
    (property "License" "Apache-2.0")
    (property "MPN" "C1005X5R1E474M050BB")
    (property "Manufacturer" "TDK")
    (property "Public" "False")
    (property "Sheetfile" "ethernet.kicad_sch")
    (property "Sheetname" "Ethernet")
    (property "Val" "470n")
    (property "Voltage" "")
    (property "ki_description" "SMD Multilayer Ceramic Capacitor, 0.47 µF, 25 V, 0402 [1005 Metric], ± 20%, X5R, C")
    (property "ki_keywords" "0402, SMT, CAPACITOR, PASSIVE, CERAMIC, MLCC")
    (attr smd)
    (fp_text reference "C2" (at -0.06 -0.955) (layer "B.SilkS")
        (effects (font (size 0.7 0.7) (thickness 0.127)) (justify mirror))
    )
    (fp_text value "C_470n_0402" (at 0 -1.17) (layer "B.Fab")
        (effects (font (size 1 1) (thickness 0.15)) (justify mirror))
    )
    (fp_text user "License: Apache-2.0" (at -0.939 -5.799) (layer "B.Fab") hide
        (effects (font (size 0.7 0.7) (thickness 0.15)) (justify left bottom mirror))
    )
    (fp_text user "Author: Antmicro" (at -0.939 -3.399) (layer "B.Fab") hide
        (effects (font (size 0.7 0.7) (thickness 0.15)) (justify left bottom mirror))
    )
    (fp_text user "${REFERENCE}" (at 0 0) (layer "B.Fab")
        (effects (font (size 0.25 0.25) (thickness 0.04)) (justify mirror))
    )
    (fp_rect (start -0.925 0.47) (end 0.925 -0.47)
      (stroke (width 0.05) (type default)) (fill none) (layer "B.CrtYd"))
    (fp_line (start -0.494 -0.248) (end -0.494 0.25)
      (stroke (width 0.15) (type solid)) (layer "B.Fab"))
    (fp_line (start -0.494 0.25) (end 0.504 0.25)
      (stroke (width 0.15) (type solid)) (layer "B.Fab"))
    (fp_line (start 0.504 -0.248) (end -0.494 -0.248)
      (stroke (width 0.15) (type solid)) (layer "B.Fab"))
    (fp_line (start 0.504 0.25) (end 0.504 -0.248)
      (stroke (width 0.15) (type solid)) (layer "B.Fab"))
    (pad "1" smd roundrect (at -0.48 0 180) (size 0.59 0.64) (layers "B.Cu" "B.Paste" "B.Mask") (roundrect_rratio 0.25)
      (net 1 "GND") (pintype "passive"))
    (pad "2" smd roundrect (at 0.48 0 180) (size 0.59 0.64) (layers "B.Cu" "B.Paste" "B.Mask") (roundrect_rratio 0.25)
      (net 211 "VCC1V2") (pintype "passive"))
  )
	(footprint "antmicro-footprints:FB_0603_1608Metric" (layer "B.Cu")
    (at 103.2 90.25 90)
    (property "Author" "Antmicro")
    (property "Current" "")
    (property "License" "Apache-2.0")
    (property "MPN" "BLM18PG121SN1D")
    (property "Manufacturer" "Murata")
    (property "Public" "False")
    (property "Sheetfile" "ethernet.kicad_sch")
    (property "Sheetname" "Ethernet")
    (property "Val" "120Z/2A")
    (property "ki_description" "Ferrite Bead, 0603 [1608 Metric], 120 ohm, 2 A, BLM18P, 0.05 ohm, ± 25%, DC power line")
    (property "ki_keywords" "0603, SMT, FERRITE BEAD, PASSIVE")
    (attr smd)
    (fp_text reference "FB2" (at 2.3 -0.1 -90) (layer "B.SilkS")
        (effects (font (size 0.7 0.7) (thickness 0.127)) (justify mirror))
    )
    (fp_text value "FB_120Z_2A_Murata-BLM18PG_0603" (at 0 -1.9 -90) (layer "B.Fab")
        (effects (font (size 1 1) (thickness 0.15)) (justify mirror))
    )
    (fp_text user "License: Apache-2.0" (at -1.653 -5.9 270) (layer "B.Fab") hide
        (effects (font (size 0.7 0.7) (thickness 0.15)) (justify left bottom mirror))
    )
    (fp_text user "${REFERENCE}" (at -1.653 -4.6 270) (layer "B.Fab") hide
        (effects (font (size 0.7 0.7) (thickness 0.15)) (justify left bottom mirror))
    )
    (fp_text user "Author: Antmicro" (at -1.653 -3.162 270) (layer "B.Fab") hide
        (effects (font (size 0.7 0.7) (thickness 0.15)) (justify left bottom mirror))
    )
    (fp_line (start -0.15 -0.4) (end 0.15 -0.4)
      (stroke (width 0.15) (type solid)) (layer "B.SilkS"))
    (fp_line (start -0.15 0.4) (end 0.15 0.4)
      (stroke (width 0.15) (type solid)) (layer "B.SilkS"))
    (fp_rect (start -1.25 0.65) (end 1.25 -0.65)
      (stroke (width 0.05) (type solid)) (fill none) (layer "B.CrtYd"))
    (fp_line (start -0.803 -0.406) (end -0.803 0.408)
      (stroke (width 0.15) (type solid)) (layer "B.Fab"))
    (fp_line (start 0.8 -0.406) (end -0.803 -0.406)
      (stroke (width 0.15) (type solid)) (layer "B.Fab"))
    (fp_line (start 0.8 0.408) (end -0.803 0.408)
      (stroke (width 0.15) (type solid)) (layer "B.Fab"))
    (fp_line (start 0.8 0.408) (end 0.8 -0.406)
      (stroke (width 0.15) (type solid)) (layer "B.Fab"))
    (pad "1" smd roundrect (at -0.7 0 90) (size 0.8 1) (layers "B.Cu" "B.Paste" "B.Mask") (roundrect_rratio 0.2)
      (net 9 "/Ethernet/AVDDL") (pintype "passive"))
    (pad "2" smd roundrect (at 0.7 0 90) (size 0.8 1) (layers "B.Cu" "B.Paste" "B.Mask") (roundrect_rratio 0.2)
      (net 211 "VCC1V2") (pintype "passive"))
  )
	(footprint "antmicro-footprints:FB_0603_1608Metric" (layer "B.Cu")
    (at 98.1 91.75 90)
    (property "Author" "Antmicro")
    (property "Current" "")
    (property "License" "Apache-2.0")
    (property "MPN" "BLM18PG121SN1D")
    (property "Manufacturer" "Murata")
    (property "Public" "False")
    (property "Sheetfile" "ethernet.kicad_sch")
    (property "Sheetname" "Ethernet")
    (property "Val" "120Z/2A")
    (property "ki_description" "Ferrite Bead, 0603 [1608 Metric], 120 ohm, 2 A, BLM18P, 0.05 ohm, ± 25%, DC power line")
    (property "ki_keywords" "0603, SMT, FERRITE BEAD, PASSIVE")
    (attr smd)
    (fp_text reference "FB1" (at -0.035 -1.15 90) (layer "B.SilkS")
        (effects (font (size 0.7 0.7) (thickness 0.127)) (justify mirror))
    )
    (fp_text value "FB_120Z_2A_Murata-BLM18PG_0603" (at 0 -1.9 90) (layer "B.Fab")
        (effects (font (size 1 1) (thickness 0.15)) (justify mirror))
    )
    (fp_text user "License: Apache-2.0" (at -1.653 -5.9 270) (layer "B.Fab") hide
        (effects (font (size 0.7 0.7) (thickness 0.15)) (justify left bottom mirror))
    )
    (fp_text user "Author: Antmicro" (at -1.653 -3.162 270) (layer "B.Fab") hide
        (effects (font (size 0.7 0.7) (thickness 0.15)) (justify left bottom mirror))
    )
    (fp_text user "${REFERENCE}" (at -1.653 -4.6 270) (layer "B.Fab") hide
        (effects (font (size 0.7 0.7) (thickness 0.15)) (justify left bottom mirror))
    )
    (fp_line (start -0.15 -0.4) (end 0.15 -0.4)
      (stroke (width 0.15) (type solid)) (layer "B.SilkS"))
    (fp_line (start -0.15 0.4) (end 0.15 0.4)
      (stroke (width 0.15) (type solid)) (layer "B.SilkS"))
    (fp_rect (start -1.25 0.65) (end 1.25 -0.65)
      (stroke (width 0.05) (type solid)) (fill none) (layer "B.CrtYd"))
    (fp_line (start -0.803 -0.406) (end -0.803 0.408)
      (stroke (width 0.15) (type solid)) (layer "B.Fab"))
    (fp_line (start 0.8 -0.406) (end -0.803 -0.406)
      (stroke (width 0.15) (type solid)) (layer "B.Fab"))
    (fp_line (start 0.8 0.408) (end -0.803 0.408)
      (stroke (width 0.15) (type solid)) (layer "B.Fab"))
    (fp_line (start 0.8 0.408) (end 0.8 -0.406)
      (stroke (width 0.15) (type solid)) (layer "B.Fab"))
    (pad "1" smd roundrect (at -0.7 0 90) (size 0.8 1) (layers "B.Cu" "B.Paste" "B.Mask") (roundrect_rratio 0.2)
      (net 2 "VCC3V3") (pintype "passive"))
    (pad "2" smd roundrect (at 0.7 0 90) (size 0.8 1) (layers "B.Cu" "B.Paste" "B.Mask") (roundrect_rratio 0.2)
      (net 4 "/Ethernet/AVDDH") (pintype "passive"))
  )
	(footprint "antmicro-footprints:C_0402_1005Metric" (layer "B.Cu")
    (at 108.95 95.65 180)
    (descr "Capacitor SMD 0402")
    (tags "capacitor SMD 0402")
    (property "Author" "Antmicro")
    (property "Dielectric" "X7R")
    (property "License" "Apache-2.0")
    (property "MPN" "GRM155R71H103KA88D")
    (property "Manufacturer" "Murata")
    (property "Public" "False")
    (property "Sheetfile" "ethernet.kicad_sch")
    (property "Sheetname" "Ethernet")
    (property "Val" "10n")
    (property "Voltage" "50V")
    (property "ki_description" "SMD Multilayer Ceramic Capacitor, 10000 pF, 50 V, 0402 [1005 Metric], ± 10%, X7R, GRM Series")
    (property "ki_keywords" "0402, SMT, CAPACITOR, PASSIVE")
    (attr smd)
    (fp_text reference "C25" (at 0.1 5.0525) (layer "B.SilkS")
        (effects (font (size 0.7 0.7) (thickness 0.127)) (justify mirror))
    )
    (fp_text value "C_10n_0402" (at 0 -1.17) (layer "B.Fab")
        (effects (font (size 1 1) (thickness 0.15)) (justify mirror))
    )
    (fp_text user "${REFERENCE}" (at 0 0) (layer "B.Fab")
        (effects (font (size 0.25 0.25) (thickness 0.04)) (justify mirror))
    )
    (fp_text user "Author: Antmicro" (at -0.939 -3.399) (layer "B.Fab") hide
        (effects (font (size 0.7 0.7) (thickness 0.15)) (justify left bottom mirror))
    )
    (fp_text user "License: Apache-2.0" (at -0.939 -5.799) (layer "B.Fab") hide
        (effects (font (size 0.7 0.7) (thickness 0.15)) (justify left bottom mirror))
    )
    (fp_rect (start -0.925 0.47) (end 0.925 -0.47)
      (stroke (width 0.05) (type default)) (fill none) (layer "B.CrtYd"))
    (fp_line (start -0.494 -0.248) (end -0.494 0.25)
      (stroke (width 0.15) (type solid)) (layer "B.Fab"))
    (fp_line (start -0.494 0.25) (end 0.504 0.25)
      (stroke (width 0.15) (type solid)) (layer "B.Fab"))
    (fp_line (start 0.504 -0.248) (end -0.494 -0.248)
      (stroke (width 0.15) (type solid)) (layer "B.Fab"))
    (fp_line (start 0.504 0.25) (end 0.504 -0.248)
      (stroke (width 0.15) (type solid)) (layer "B.Fab"))
    (pad "1" smd roundrect (at -0.48 0 180) (size 0.59 0.64) (layers "B.Cu" "B.Paste" "B.Mask") (roundrect_rratio 0.25)
      (net 1 "GND") (pintype "passive"))
    (pad "2" smd roundrect (at 0.48 0 180) (size 0.59 0.64) (layers "B.Cu" "B.Paste" "B.Mask") (roundrect_rratio 0.25)
      (net 10 "/Ethernet/AVDDL_PLL") (pintype "passive"))
  )
	(footprint "antmicro-footprints:C_0402_1005Metric" (layer "B.Cu")
    (at 106.3 95.7)
    (descr "Capacitor SMD 0402")
    (tags "capacitor SMD 0402")
    (property "Author" "Antmicro")
    (property "Dielectric" "X5R")
    (property "License" "Apache-2.0")
    (property "MPN" "GRM155R61H104KE14D")
    (property "Manufacturer" "Murata")
    (property "Public" "False")
    (property "Sheetfile" "ethernet.kicad_sch")
    (property "Sheetname" "Ethernet")
    (property "Val" "100n")
    (property "Voltage" "50V")
    (property "ki_description" "SMD Multilayer Ceramic Capacitor, 0.1 µF, 50 V, 0402 [1005 Metric], ± 10%, X5R, GRM Series")
    (property "ki_keywords" "0402, SMT, CAPACITOR, PASSIVE, CERAMIC, MLCC")
    (attr smd)
    (fp_text reference "C24" (at -1.91 0.005) (layer "B.SilkS")
        (effects (font (size 0.7 0.7) (thickness 0.127)) (justify mirror))
    )
    (fp_text value "C_100n_0402" (at 0 -1.17) (layer "B.Fab")
        (effects (font (size 1 1) (thickness 0.15)) (justify mirror))
    )
    (fp_text user "License: Apache-2.0" (at -0.939 -5.799 180) (layer "B.Fab") hide
        (effects (font (size 0.7 0.7) (thickness 0.15)) (justify left bottom mirror))
    )
    (fp_text user "${REFERENCE}" (at 0 0) (layer "B.Fab")
        (effects (font (size 0.25 0.25) (thickness 0.04)) (justify mirror))
    )
    (fp_text user "Author: Antmicro" (at -0.939 -3.399 180) (layer "B.Fab") hide
        (effects (font (size 0.7 0.7) (thickness 0.15)) (justify left bottom mirror))
    )
    (fp_rect (start -0.925 0.47) (end 0.925 -0.47)
      (stroke (width 0.05) (type default)) (fill none) (layer "B.CrtYd"))
    (fp_line (start -0.494 -0.248) (end -0.494 0.25)
      (stroke (width 0.15) (type solid)) (layer "B.Fab"))
    (fp_line (start -0.494 0.25) (end 0.504 0.25)
      (stroke (width 0.15) (type solid)) (layer "B.Fab"))
    (fp_line (start 0.504 -0.248) (end -0.494 -0.248)
      (stroke (width 0.15) (type solid)) (layer "B.Fab"))
    (fp_line (start 0.504 0.25) (end 0.504 -0.248)
      (stroke (width 0.15) (type solid)) (layer "B.Fab"))
    (pad "1" smd roundrect (at -0.48 0) (size 0.59 0.64) (layers "B.Cu" "B.Paste" "B.Mask") (roundrect_rratio 0.25)
      (net 1 "GND") (pintype "passive"))
    (pad "2" smd roundrect (at 0.48 0) (size 0.59 0.64) (layers "B.Cu" "B.Paste" "B.Mask") (roundrect_rratio 0.25)
      (net 10 "/Ethernet/AVDDL_PLL") (pintype "passive"))
  )
)
